(kicad_pcb
	(version 20241229)
	(generator "pcbnew")
	(generator_version "9.0")
	(general
		(thickness 1.61)
		(legacy_teardrops no)
	)
	(paper "A3")
	(title_block
		(title "RDIMM DDR5 Tester")
		(date "2026-05-21")
		(rev "2.2.0")
		(company "Antmicro")
		(comment 9 "footprints 651-655 of 796")
	)
	(layers
		(0 "F.Cu" signal)
		(4 "In1.Cu" power)
		(6 "In2.Cu" mixed)
		(8 "In3.Cu" power)
		(10 "In4.Cu" mixed)
		(12 "In5.Cu" power)
		(14 "In6.Cu" mixed)
		(16 "In7.Cu" power)
		(18 "In8.Cu" power)
		(20 "In9.Cu" mixed)
		(22 "In10.Cu" power)
		(2 "B.Cu" signal)
		(9 "F.Adhes" user "F.Adhesive")
		(11 "B.Adhes" user "B.Adhesive")
		(13 "F.Paste" user)
		(15 "B.Paste" user)
		(5 "F.SilkS" user "F.Silkscreen")
		(7 "B.SilkS" user "B.Silkscreen")
		(1 "F.Mask" user)
		(3 "B.Mask" user)
		(17 "Dwgs.User" user "User.Drawings")
		(19 "Cmts.User" user "User.Comments")
		(21 "Eco1.User" user "User.Eco1")
		(23 "Eco2.User" user "User.Eco2")
		(25 "Edge.Cuts" user)
		(27 "Margin" user)
		(31 "F.CrtYd" user "F.Courtyard")
		(29 "B.CrtYd" user "B.Courtyard")
		(35 "F.Fab" user)
		(33 "B.Fab" user)
	)
	(footprint "antmicro-footprints:C_0402_1005Metric_EIA"
		(layer "B.Cu")
		(at 191 150.5 90)
		(descr "Capacitor SMD 0402 (1005 Metric), square (rectangular) end terminal, IPC_7351 nominal, (Body size source: IPC-SM-782 page 76, https://www.pcb-3d.com/wordpress/wp-content/uploads/ipc-sm-782a_amendment_1_and_2.pdf)")
		(tags "capacitor 0402")
		(property "Reference" "C64"
			(at 9.8 -30.625 90)
			(layer "B.SilkS")
			(effects
				(font
					(size 0.7 0.7)
					(thickness 0.15)
				)
				(justify right bottom mirror)
			)
		)
		(property "Value" "C_100n_0402"
			(at 0 -1.169 90)
			(layer "B.Fab")
			(effects
				(font
					(size 0.7 0.7)
					(thickness 0.15)
				)
				(justify right bottom mirror)
			)
		)
		(property "Datasheet" "https://www.murata.com/products/productdetail?partno=GRM155R61H104KE14%23"
			(at 0 0 90)
			(layer "F.Fab")
			(hide yes)
			(effects
				(font
					(size 1.27 1.27)
					(thickness 0.15)
				)
			)
		)
		(property "MPN" "GRM155R61H104KE14D"
			(at 0 0 90)
			(unlocked yes)
			(layer "B.Fab")
			(hide yes)
			(effects
				(font
					(size 1 1)
					(thickness 0.15)
				)
				(justify mirror)
			)
		)
		(property "Manufacturer" "Murata"
			(at 0 0 90)
			(unlocked yes)
			(layer "B.Fab")
			(hide yes)
			(effects
				(font
					(size 1 1)
					(thickness 0.15)
				)
				(justify mirror)
			)
		)
		(property "License" "Apache-2.0"
			(at 0 0 90)
			(unlocked yes)
			(layer "B.Fab")
			(hide yes)
			(effects
				(font
					(size 1 1)
					(thickness 0.15)
				)
				(justify mirror)
			)
		)
		(property "Author" "Antmicro"
			(at 0 0 90)
			(unlocked yes)
			(layer "B.Fab")
			(hide yes)
			(effects
				(font
					(size 1 1)
					(thickness 0.15)
				)
				(justify mirror)
			)
		)
		(property "Val" "100n"
			(at 0 0 90)
			(unlocked yes)
			(layer "B.Fab")
			(hide yes)
			(effects
				(font
					(size 1 1)
					(thickness 0.15)
				)
				(justify mirror)
			)
		)
		(property "Voltage" "50V"
			(at 0 0 90)
			(unlocked yes)
			(layer "B.Fab")
			(hide yes)
			(effects
				(font
					(size 1 1)
					(thickness 0.15)
				)
				(justify mirror)
			)
		)
		(property "Dielectric" "X5R"
			(at 0 0 90)
			(unlocked yes)
			(layer "B.Fab")
			(hide yes)
			(effects
				(font
					(size 1 1)
					(thickness 0.15)
				)
				(justify mirror)
			)
		)
		(sheetname "/FPGA power/")
		(sheetfile "fpga-power.kicad_sch")
		(attr smd)
		(fp_rect
			(start -0.95 0.45)
			(end 0.95 -0.45)
			(stroke
				(width 0.05)
				(type default)
			)
			(fill no)
			(layer "B.CrtYd")
		)
		(fp_line
			(start 0.498 -0.248)
			(end -0.5 -0.248)
			(stroke
				(width 0.15)
				(type solid)
			)
			(layer "B.Fab")
		)
		(fp_line
			(start -0.5 -0.248)
			(end -0.5 0.25)
			(stroke
				(width 0.15)
				(type solid)
			)
			(layer "B.Fab")
		)
		(fp_line
			(start 0.498 0.25)
			(end 0.498 -0.248)
			(stroke
				(width 0.15)
				(type solid)
			)
			(layer "B.Fab")
		)
		(fp_line
			(start -0.5 0.25)
			(end 0.498 0.25)
			(stroke
				(width 0.15)
				(type solid)
			)
			(layer "B.Fab")
		)
		(fp_text user "License: Apache-2.0"
			(at -0.9656 -4.369 270)
			(layer "B.Fab")
			(effects
				(font
					(size 0.7 0.7)
					(thickness 0.15)
				)
				(justify left bottom mirror)
			)
		)
		(fp_text user "Author: Antmicro"
			(at -0.9656 -5.569 270)
			(layer "B.Fab")
			(effects
				(font
					(size 0.7 0.7)
					(thickness 0.15)
				)
				(justify left bottom mirror)
			)
		)
		(fp_text user "${REFERENCE}"
			(at -0.9656 -3.169 270)
			(layer "B.Fab")
			(effects
				(font
					(size 0.7 0.7)
					(thickness 0.15)
				)
				(justify left bottom mirror)
			)
		)
		(pad "1" smd roundrect
			(at -0.5 0)
			(size 0.6 0.6)
			(layers "B.Cu" "B.Mask" "B.Paste")
			(roundrect_rratio 0.25)
			(net 1 "GND")
			(pintype "passive")
		)
		(pad "2" smd roundrect
			(at 0.498 0 90)
			(size 0.6 0.6)
			(layers "B.Cu" "B.Mask" "B.Paste")
			(roundrect_rratio 0.25)
			(net 553 "+0V85")
			(pintype "passive")
		)
	)
	(footprint "antmicro-footprints:C_0402_1005Metric"
		(layer "B.Cu")
		(at 206.18 141.6045 180)
		(descr "Capacitor SMD 0402")
		(tags "capacitor SMD 0402")
		(property "Reference" "C329"
			(at -2.32 0.0045 0)
			(layer "B.SilkS")
			(effects
				(font
					(size 0.7 0.7)
					(thickness 0.15)
				)
				(justify mirror)
			)
		)
		(property "Value" "C_10u_6.3V_0402"
			(at -1.022927 -2.155213 0)
			(layer "B.Fab")
			(effects
				(font
					(size 0.7 0.7)
					(thickness 0.15)
				)
				(justify left bottom mirror)
			)
		)
		(property "Datasheet" "https://www.murata.com/products/productdetail?partno=GRM155R60J106ME15%23"
			(at 0 0 0)
			(layer "B.Fab")
			(hide yes)
			(effects
				(font
					(size 1.27 1.27)
					(thickness 0.15)
				)
				(justify mirror)
			)
		)
		(property "MPN" "GRM155R60J106ME15D"
			(at 0 0 0)
			(unlocked yes)
			(layer "B.Fab")
			(hide yes)
			(effects
				(font
					(size 1 1)
					(thickness 0.15)
				)
				(justify mirror)
			)
		)
		(property "Manufacturer" "Murata"
			(at 0 0 0)
			(unlocked yes)
			(layer "B.Fab")
			(hide yes)
			(effects
				(font
					(size 1 1)
					(thickness 0.15)
				)
				(justify mirror)
			)
		)
		(property "License" "Apache-2.0"
			(at 0 0 0)
			(unlocked yes)
			(layer "B.Fab")
			(hide yes)
			(effects
				(font
					(size 1 1)
					(thickness 0.15)
				)
				(justify mirror)
			)
		)
		(property "Author" "Antmicro"
			(at 0 0 0)
			(unlocked yes)
			(layer "B.Fab")
			(hide yes)
			(effects
				(font
					(size 1 1)
					(thickness 0.15)
				)
				(justify mirror)
			)
		)
		(property "Val" "10u"
			(at 0 0 0)
			(unlocked yes)
			(layer "B.Fab")
			(hide yes)
			(effects
				(font
					(size 1 1)
					(thickness 0.15)
				)
				(justify mirror)
			)
		)
		(property "Voltage" "6.3V"
			(at 0 0 0)
			(unlocked yes)
			(layer "B.Fab")
			(hide yes)
			(effects
				(font
					(size 1 1)
					(thickness 0.15)
				)
				(justify mirror)
			)
		)
		(property "Dielectric" "X5R"
			(at 0 0 0)
			(unlocked yes)
			(layer "B.Fab")
			(hide yes)
			(effects
				(font
					(size 1 1)
					(thickness 0.15)
				)
				(justify mirror)
			)
		)
		(sheetname "/Supply/")
		(sheetfile "supply.kicad_sch")
		(attr smd)
		(fp_rect
			(start -0.925 0.47)
			(end 0.925 -0.47)
			(stroke
				(width 0.05)
				(type default)
			)
			(fill no)
			(layer "B.CrtYd")
		)
		(fp_line
			(start 0.504 0.25)
			(end 0.504 -0.248)
			(stroke
				(width 0.15)
				(type solid)
			)
			(layer "B.Fab")
		)
		(fp_line
			(start 0.504 -0.248)
			(end -0.494 -0.248)
			(stroke
				(width 0.15)
				(type solid)
			)
			(layer "B.Fab")
		)
		(fp_line
			(start -0.494 0.25)
			(end 0.504 0.25)
			(stroke
				(width 0.15)
				(type solid)
			)
			(layer "B.Fab")
		)
		(fp_line
			(start -0.494 -0.248)
			(end -0.494 0.25)
			(stroke
				(width 0.15)
				(type solid)
			)
			(layer "B.Fab")
		)
		(fp_text user "License: Apache-2.0"
			(at -0.939 -5.799 0)
			(layer "B.Fab")
			(effects
				(font
					(size 0.7 0.7)
					(thickness 0.15)
				)
				(justify left bottom mirror)
			)
		)
		(fp_text user "${REFERENCE}"
			(at -0.939 -4.599 0)
			(layer "B.Fab")
			(effects
				(font
					(size 0.7 0.7)
					(thickness 0.15)
				)
				(justify left bottom mirror)
			)
		)
		(fp_text user "Author: Antmicro"
			(at -0.939 -3.399 0)
			(layer "B.Fab")
			(effects
				(font
					(size 0.7 0.7)
					(thickness 0.15)
				)
				(justify left bottom mirror)
			)
		)
		(pad "1" smd roundrect
			(at -0.48 0 180)
			(size 0.59 0.64)
			(layers "B.Cu" "B.Mask" "B.Paste")
			(roundrect_rratio 0.25)
			(net 1 "GND")
			(pintype "passive")
		)
		(pad "2" smd roundrect
			(at 0.48 0 180)
			(size 0.59 0.64)
			(layers "B.Cu" "B.Mask" "B.Paste")
			(roundrect_rratio 0.25)
			(net 151 "+3V3")
			(pintype "passive")
		)
	)
	(footprint "antmicro-footprints:R_0402_1005Metric"
		(layer "B.Cu")
		(at 209.89 153.1505 180)
		(descr "Resistor SMD 0402")
		(tags "resistor SMD 0402")
		(property "Reference" "R9"
			(at 0.96 0.0405 0)
			(layer "B.SilkS")
			(effects
				(font
					(size 0.7 0.7)
					(thickness 0.15)
				)
				(justify left bottom mirror)
			)
		)
		(property "Value" "R_22R_0402"
			(at -1.011843 -1.772047 0)
			(layer "B.Fab")
			(effects
				(font
					(size 0.7 0.7)
					(thickness 0.15)
				)
				(justify left bottom mirror)
			)
		)
		(property "Datasheet" "https://www.bourns.com/docs/product-datasheets/cr.pdf"
			(at 0 0 180)
			(layer "F.Fab")
			(hide yes)
			(effects
				(font
					(size 1.27 1.27)
					(thickness 0.15)
				)
			)
		)
		(property "Manufacturer" "Bourns"
			(at 0 0 180)
			(unlocked yes)
			(layer "B.Fab")
			(hide yes)
			(effects
				(font
					(size 1 1)
					(thickness 0.15)
				)
				(justify mirror)
			)
		)
		(property "MPN" "CR0402-FX-22R0GLF"
			(at 0 0 180)
			(unlocked yes)
			(layer "B.Fab")
			(hide yes)
			(effects
				(font
					(size 1 1)
					(thickness 0.15)
				)
				(justify mirror)
			)
		)
		(property "Val" "22R"
			(at 0 0 180)
			(unlocked yes)
			(layer "B.Fab")
			(hide yes)
			(effects
				(font
					(size 1 1)
					(thickness 0.15)
				)
				(justify mirror)
			)
		)
		(property "License" "Apache-2.0"
			(at 0 0 180)
			(unlocked yes)
			(layer "B.Fab")
			(hide yes)
			(effects
				(font
					(size 1 1)
					(thickness 0.15)
				)
				(justify mirror)
			)
		)
		(property "Author" "Antmicro"
			(at 0 0 180)
			(unlocked yes)
			(layer "B.Fab")
			(hide yes)
			(effects
				(font
					(size 1 1)
					(thickness 0.15)
				)
				(justify mirror)
			)
		)
		(property "Tolerance" "1%"
			(at 0 0 180)
			(unlocked yes)
			(layer "B.Fab")
			(hide yes)
			(effects
				(font
					(size 1 1)
					(thickness 0.15)
				)
				(justify mirror)
			)
		)
		(sheetname "/HyperRAM + QSPI Flash/")
		(sheetfile "hyperram-flash.kicad_sch")
		(attr smd)
		(fp_rect
			(start -0.925 0.47)
			(end 0.925 -0.47)
			(stroke
				(width 0.05)
				(type default)
			)
			(fill no)
			(layer "B.CrtYd")
		)
		(fp_rect
			(start -0.5 0.25)
			(end 0.5 -0.25)
			(stroke
				(width 0.15)
				(type solid)
			)
			(fill no)
			(layer "B.Fab")
		)
		(fp_text user "${REFERENCE}"
			(at -0.95 -3.168 0)
			(layer "B.Fab")
			(effects
				(font
					(size 0.7 0.7)
					(thickness 0.15)
				)
				(justify left bottom mirror)
			)
		)
		(fp_text user "License: Apache-2.0"
			(at -0.95 -5.169 0)
			(layer "B.Fab")
			(effects
				(font
					(size 0.7 0.7)
					(thickness 0.15)
				)
				(justify left bottom mirror)
			)
		)
		(fp_text user "Author: Antmicro"
			(at -0.95 -4.169 0)
			(layer "B.Fab")
			(effects
				(font
					(size 0.7 0.7)
					(thickness 0.15)
				)
				(justify left bottom mirror)
			)
		)
		(pad "1" smd roundrect
			(at -0.48 0 180)
			(size 0.59 0.64)
			(layers "B.Cu" "B.Mask" "B.Paste")
			(roundrect_rratio 0.25)
			(net 279 "/HyperRAM + QSPI Flash/IO3")
			(pintype "passive")
		)
		(pad "2" smd roundrect
			(at 0.48 0 180)
			(size 0.59 0.64)
			(layers "B.Cu" "B.Mask" "B.Paste")
			(roundrect_rratio 0.25)
			(net 354 "/FPGA Config/FLASH.IO3")
			(pintype "passive")
		)
	)
	(footprint "antmicro-footprints:R_0402_1005Metric"
		(layer "B.Cu")
		(at 206.325 154.19 -90)
		(descr "Resistor SMD 0402")
		(tags "resistor SMD 0402")
		(property "Reference" "R39"
			(at 1.36 -0.405 90)
			(layer "B.SilkS")
			(effects
				(font
					(size 0.7 0.7)
					(thickness 0.15)
				)
				(justify left bottom mirror)
			)
		)
		(property "Value" "R_4k7_0402"
			(at -1.011843 -1.772047 90)
			(layer "B.Fab")
			(effects
				(font
					(size 0.7 0.7)
					(thickness 0.15)
				)
				(justify left bottom mirror)
			)
		)
		(property "Datasheet" "https://www.bourns.com/docs/product-datasheets/cr.pdf"
			(at 0 0 270)
			(layer "F.Fab")
			(hide yes)
			(effects
				(font
					(size 1.27 1.27)
					(thickness 0.15)
				)
			)
		)
		(property "MPN" "CR0402-FX-4701GLF"
			(at 0 0 270)
			(unlocked yes)
			(layer "B.Fab")
			(hide yes)
			(effects
				(font
					(size 1 1)
					(thickness 0.15)
				)
				(justify mirror)
			)
		)
		(property "Manufacturer" "Bourns"
			(at 0 0 270)
			(unlocked yes)
			(layer "B.Fab")
			(hide yes)
			(effects
				(font
					(size 1 1)
					(thickness 0.15)
				)
				(justify mirror)
			)
		)
		(property "License" "Apache-2.0"
			(at 0 0 270)
			(unlocked yes)
			(layer "B.Fab")
			(hide yes)
			(effects
				(font
					(size 1 1)
					(thickness 0.15)
				)
				(justify mirror)
			)
		)
		(property "Author" "Antmicro"
			(at 0 0 270)
			(unlocked yes)
			(layer "B.Fab")
			(hide yes)
			(effects
				(font
					(size 1 1)
					(thickness 0.15)
				)
				(justify mirror)
			)
		)
		(property "Val" "4k7"
			(at 0 0 270)
			(unlocked yes)
			(layer "B.Fab")
			(hide yes)
			(effects
				(font
					(size 1 1)
					(thickness 0.15)
				)
				(justify mirror)
			)
		)
		(property "Tolerance" "1%"
			(at 0 0 270)
			(unlocked yes)
			(layer "B.Fab")
			(hide yes)
			(effects
				(font
					(size 1 1)
					(thickness 0.15)
				)
				(justify mirror)
			)
		)
		(sheetname "/FPGA Config/")
		(sheetfile "fpga-config.kicad_sch")
		(attr smd)
		(fp_rect
			(start -0.925 0.47)
			(end 0.925 -0.47)
			(stroke
				(width 0.05)
				(type default)
			)
			(fill no)
			(layer "B.CrtYd")
		)
		(fp_rect
			(start -0.5 0.25)
			(end 0.5 -0.25)
			(stroke
				(width 0.15)
				(type solid)
			)
			(fill no)
			(layer "B.Fab")
		)
		(fp_text user "Author: Antmicro"
			(at -0.95 -4.169 90)
			(layer "B.Fab")
			(effects
				(font
					(size 0.7 0.7)
					(thickness 0.15)
				)
				(justify left bottom mirror)
			)
		)
		(fp_text user "License: Apache-2.0"
			(at -0.95 -5.169 90)
			(layer "B.Fab")
			(effects
				(font
					(size 0.7 0.7)
					(thickness 0.15)
				)
				(justify left bottom mirror)
			)
		)
		(fp_text user "${REFERENCE}"
			(at -0.95 -3.168 90)
			(layer "B.Fab")
			(effects
				(font
					(size 0.7 0.7)
					(thickness 0.15)
				)
				(justify left bottom mirror)
			)
		)
		(pad "1" smd roundrect
			(at -0.48 0 270)
			(size 0.59 0.64)
			(layers "B.Cu" "B.Mask" "B.Paste")
			(roundrect_rratio 0.25)
			(net 151 "+3V3")
			(pintype "passive")
		)
		(pad "2" smd roundrect
			(at 0.48 0 270)
			(size 0.59 0.64)
			(layers "B.Cu" "B.Mask" "B.Paste")
			(roundrect_rratio 0.25)
			(net 705 "/FPGA Config/~{THERM}")
			(pintype "passive")
		)
	)
	(footprint "antmicro-footprints:C_0402_1005Metric_EIA"
		(layer "B.Cu")
		(at 187 158.5 90)
		(descr "Capacitor SMD 0402 (1005 Metric), square (rectangular) end terminal, IPC_7351 nominal, (Body size source: IPC-SM-782 page 76, https://www.pcb-3d.com/wordpress/wp-content/uploads/ipc-sm-782a_amendment_1_and_2.pdf)")
		(tags "capacitor 0402")
		(property "Reference" "C50"
			(at 9.5 -30.675 90)
			(layer "B.SilkS")
			(effects
				(font
					(size 0.7 0.7)
					(thickness 0.15)
				)
				(justify right bottom mirror)
			)
		)
		(property "Value" "C_1u_25V_0402"
			(at 0 -1.169 90)
			(layer "B.Fab")
			(effects
				(font
					(size 0.7 0.7)
					(thickness 0.15)
				)
				(justify right bottom mirror)
			)
		)
		(property "Datasheet" "https://www.murata.com/products/productdetail?partno=GRM155R61E105KE11%23"
			(at 0 0 90)
			(layer "F.Fab")
			(hide yes)
			(effects
				(font
					(size 1.27 1.27)
					(thickness 0.15)
				)
			)
		)
		(property "MPN" "GRM155R61E105KE11J"
			(at 0 0 90)
			(unlocked yes)
			(layer "B.Fab")
			(hide yes)
			(effects
				(font
					(size 1 1)
					(thickness 0.15)
				)
				(justify mirror)
			)
		)
		(property "Manufacturer" "Murata"
			(at 0 0 90)
			(unlocked yes)
			(layer "B.Fab")
			(hide yes)
			(effects
				(font
					(size 1 1)
					(thickness 0.15)
				)
				(justify mirror)
			)
		)
		(property "License" "Apache-2.0"
			(at 0 0 90)
			(unlocked yes)
			(layer "B.Fab")
			(hide yes)
			(effects
				(font
					(size 1 1)
					(thickness 0.15)
				)
				(justify mirror)
			)
		)
		(property "Author" "Antmicro"
			(at 0 0 90)
			(unlocked yes)
			(layer "B.Fab")
			(hide yes)
			(effects
				(font
					(size 1 1)
					(thickness 0.15)
				)
				(justify mirror)
			)
		)
		(property "Val" "1u"
			(at 0 0 90)
			(unlocked yes)
			(layer "B.Fab")
			(hide yes)
			(effects
				(font
					(size 1 1)
					(thickness 0.15)
				)
				(justify mirror)
			)
		)
		(property "Voltage" "25V"
			(at 0 0 90)
			(unlocked yes)
			(layer "B.Fab")
			(hide yes)
			(effects
				(font
					(size 1 1)
					(thickness 0.15)
				)
				(justify mirror)
			)
		)
		(property "Dielectric" "X5R"
			(at 0 0 90)
			(unlocked yes)
			(layer "B.Fab")
			(hide yes)
			(effects
				(font
					(size 1 1)
					(thickness 0.15)
				)
				(justify mirror)
			)
		)
		(sheetname "/FPGA power/")
		(sheetfile "fpga-power.kicad_sch")
		(attr smd)
		(fp_rect
			(start -0.95 0.45)
			(end 0.95 -0.45)
			(stroke
				(width 0.05)
				(type default)
			)
			(fill no)
			(layer "B.CrtYd")
		)
		(fp_line
			(start 0.498 -0.248)
			(end -0.5 -0.248)
			(stroke
				(width 0.15)
				(type solid)
			)
			(layer "B.Fab")
		)
		(fp_line
			(start -0.5 -0.248)
			(end -0.5 0.25)
			(stroke
				(width 0.15)
				(type solid)
			)
			(layer "B.Fab")
		)
		(fp_line
			(start 0.498 0.25)
			(end 0.498 -0.248)
			(stroke
				(width 0.15)
				(type solid)
			)
			(layer "B.Fab")
		)
		(fp_line
			(start -0.5 0.25)
			(end 0.498 0.25)
			(stroke
				(width 0.15)
				(type solid)
			)
			(layer "B.Fab")
		)
		(fp_text user "License: Apache-2.0"
			(at -0.9656 -4.369 270)
			(layer "B.Fab")
			(effects
				(font
					(size 0.7 0.7)
					(thickness 0.15)
				)
				(justify left bottom mirror)
			)
		)
		(fp_text user "${REFERENCE}"
			(at -0.9656 -3.169 270)
			(layer "B.Fab")
			(effects
				(font
					(size 0.7 0.7)
					(thickness 0.15)
				)
				(justify left bottom mirror)
			)
		)
		(fp_text user "Author: Antmicro"
			(at -0.9656 -5.569 270)
			(layer "B.Fab")
			(effects
				(font
					(size 0.7 0.7)
					(thickness 0.15)
				)
				(justify left bottom mirror)
			)
		)
		(pad "1" smd roundrect
			(at -0.5 0)
			(size 0.6 0.6)
			(layers "B.Cu" "B.Mask" "B.Paste")
			(roundrect_rratio 0.25)
			(net 1 "GND")
			(pintype "passive")
		)
		(pad "2" smd roundrect
			(at 0.498 0 90)
			(size 0.6 0.6)
			(layers "B.Cu" "B.Mask" "B.Paste")
			(roundrect_rratio 0.25)
			(net 553 "+0V85")
			(pintype "passive")
		)
	)
)
